# S9S_MB_2U (Grand Teton) — schematic netlist excerpt (pin names and nets, part order shuffled) for the footprints in the layout excerpt that follows; sources: Cadence DE-HDL packaged netlist, KiCad conversion of 03242023_DA0F0TMBIJ0_F0T_Motherboard_J_brd_V01_OCP.brd

R18  Q_RES  499 1% CHIP  pkg 0402LF  page 16 : A = PVNN_TERM_CPU0 ; B = DBP_CPU_MBP0_GTL_N
PR4219  Q_RES  499 1% CHIP  pkg 0402LF  page 267 : A = PVCCIN_CPU0 ; B = GND

(kicad_pcb
	(version 20260206)
	(generator "pcbnew")
	(generator_version "10.0")
	(general
		(thickness 1.6)
		(legacy_teardrops no)
	)
	(paper "A4")
	(title_block
		(title "03242023_DA0F0TMBIJ0_F0T_Motherboard_J_brd_V01_OCP.brd")
		(comment 1 "Grand Teton / footprints 4731-4732 of 6105")
	)
	(layers
		(0 "F.Cu" signal "TOP")
		(4 "In1.Cu" signal "GND")
		(6 "In2.Cu" signal "IN1")
		(8 "In3.Cu" signal "GND1")
		(10 "In4.Cu" signal "IN2")
		(12 "In5.Cu" signal "GND2")
		(14 "In6.Cu" signal "IN3")
		(16 "In7.Cu" signal "GND3")
		(18 "In8.Cu" signal "VCC")
		(20 "In9.Cu" signal "VCC1")
		(22 "In10.Cu" signal "GND4")
		(24 "In11.Cu" signal "IN4")
		(26 "In12.Cu" signal "GND5")
		(28 "In13.Cu" signal "IN5")
		(30 "In14.Cu" signal "GND6")
		(32 "In15.Cu" signal "IN6")
		(34 "In16.Cu" signal "GND7")
		(2 "B.Cu" signal "BOTTOM")
		(9 "F.Adhes" user "F.Adhesive")
		(11 "B.Adhes" user "B.Adhesive")
		(13 "F.Paste" user "Package Geometry/Pastemask Top")
		(15 "B.Paste" user "Package Geometry/Pastemask Bottom")
		(5 "F.SilkS" user "Ref Des/Silkscreen Top")
		(7 "B.SilkS" user "Ref Des/Silkscreen Bottom")
		(1 "F.Mask" user "Board Geometry/Soldermask Top")
		(3 "B.Mask" user "Board Geometry/Soldermask Bottom")
		(17 "Dwgs.User" user "User.Drawings")
		(19 "Cmts.User" user "User.Comments")
		(21 "Eco1.User" user "User.Eco1")
		(23 "Eco2.User" user "User.Eco2")
		(25 "Edge.Cuts" user "Board Geometry/Outline")
		(27 "Margin" user)
		(31 "F.CrtYd" user "Package Geometry/Place Bound Top")
		(29 "B.CrtYd" user "Package Geometry/Place Bound Bottom")
		(35 "F.Fab" user "Ref Des/Assembly Top")
		(33 "B.Fab" user "Ref Des/Assembly Bottom")
	)
	(footprint ""
		(layer "B.Cu")
		(at 333.653638 -188.92393 -90)
		(property "Reference" "R18"
			(at 0 0 90)
			(layer "B.SilkS")
			(hide yes)
			(effects
				(font
					(size 1.27 1.27)
				)
				(justify mirror)
			)
		)
		(property "Value" ""
			(at 0 0 90)
			(layer "B.Fab")
			(effects
				(font
					(size 1.27 1.27)
				)
				(justify mirror)
			)
		)
		(duplicate_pad_numbers_are_jumpers no)
		(fp_line
			(start -0.7874 0.4064)
			(end 0.7874 0.4064)
			(stroke
				(width 0.1524)
				(type default)
			)
			(layer "B.SilkS")
		)
		(fp_line
			(start 0.7874 0.4064)
			(end 0.7874 -0.4064)
			(stroke
				(width 0.1524)
				(type default)
			)
			(layer "B.SilkS")
		)
		(fp_line
			(start -0.7874 -0.4064)
			(end -0.7874 0.4064)
			(stroke
				(width 0.1524)
				(type default)
			)
			(layer "B.SilkS")
		)
		(fp_line
			(start 0.7874 -0.4064)
			(end -0.7874 -0.4064)
			(stroke
				(width 0.1524)
				(type default)
			)
			(layer "B.SilkS")
		)
		(fp_line
			(start -0.67945 0.3048)
			(end -0.120396 0.3048)
			(stroke
				(width 0.1)
				(type default)
			)
			(layer "B.Fab")
		)
		(fp_line
			(start -0.120396 0.3048)
			(end -0.120396 0.2794)
			(stroke
				(width 0.1)
				(type default)
			)
			(layer "B.Fab")
		)
		(fp_line
			(start 0.12065 0.3048)
			(end 0.67945 0.3048)
			(stroke
				(width 0.1)
				(type default)
			)
			(layer "B.Fab")
		)
		(fp_line
			(start 0.67945 0.3048)
			(end 0.67945 -0.305054)
			(stroke
				(width 0.1)
				(type default)
			)
			(layer "B.Fab")
		)
		(fp_line
			(start -0.120396 0.2794)
			(end 0.12065 0.2794)
			(stroke
				(width 0.1)
				(type default)
			)
			(layer "B.Fab")
		)
		(fp_line
			(start 0.12065 0.2794)
			(end 0.12065 0.3048)
			(stroke
				(width 0.1)
				(type default)
			)
			(layer "B.Fab")
		)
		(fp_line
			(start -0.12065 -0.2794)
			(end -0.12065 -0.3048)
			(stroke
				(width 0.1)
				(type default)
			)
			(layer "B.Fab")
		)
		(fp_line
			(start 0.12065 -0.2794)
			(end -0.12065 -0.2794)
			(stroke
				(width 0.1)
				(type default)
			)
			(layer "B.Fab")
		)
		(fp_line
			(start -0.67945 -0.3048)
			(end -0.67945 0.3048)
			(stroke
				(width 0.1)
				(type default)
			)
			(layer "B.Fab")
		)
		(fp_line
			(start -0.12065 -0.3048)
			(end -0.67945 -0.3048)
			(stroke
				(width 0.1)
				(type default)
			)
			(layer "B.Fab")
		)
		(fp_line
			(start 0.12065 -0.305054)
			(end 0.12065 -0.2794)
			(stroke
				(width 0.1)
				(type default)
			)
			(layer "B.Fab")
		)
		(fp_line
			(start 0.67945 -0.305054)
			(end 0.12065 -0.305054)
			(stroke
				(width 0.1)
				(type default)
			)
			(layer "B.Fab")
		)
		(pad "1" smd circle
			(at 0.40005 0 90)
			(size 0 0)
			(layers "B.Cu" "B.Mask" "B.Paste")
			(net "PVNN_TERM_CPU0")
		)
		(pad "2" smd circle
			(at -0.40005 0 90)
			(size 0 0)
			(layers "B.Cu" "B.Mask" "B.Paste")
			(net "DBP_CPU_MBP0_GTL_N")
		)
	)
	(footprint ""
		(layer "B.Cu")
		(at 347.32468 -325.135748 -90)
		(property "Reference" "PR4219"
			(at 0 0 90)
			(layer "B.SilkS")
			(hide yes)
			(effects
				(font
					(size 1.27 1.27)
				)
				(justify mirror)
			)
		)
		(property "Value" ""
			(at 0 0 90)
			(layer "B.Fab")
			(effects
				(font
					(size 1.27 1.27)
				)
				(justify mirror)
			)
		)
		(duplicate_pad_numbers_are_jumpers no)
		(fp_line
			(start -0.7874 0.4064)
			(end 0.7874 0.4064)
			(stroke
				(width 0.1524)
				(type default)
			)
			(layer "B.SilkS")
		)
		(fp_line
			(start 0.7874 0.4064)
			(end 0.7874 -0.4064)
			(stroke
				(width 0.1524)
				(type default)
			)
			(layer "B.SilkS")
		)
		(fp_line
			(start -0.7874 -0.4064)
			(end -0.7874 0.4064)
			(stroke
				(width 0.1524)
				(type default)
			)
			(layer "B.SilkS")
		)
		(fp_line
			(start 0.7874 -0.4064)
			(end -0.7874 -0.4064)
			(stroke
				(width 0.1524)
				(type default)
			)
			(layer "B.SilkS")
		)
		(fp_line
			(start -0.67945 0.3048)
			(end -0.120396 0.3048)
			(stroke
				(width 0.1)
				(type default)
			)
			(layer "B.Fab")
		)
		(fp_line
			(start -0.120396 0.3048)
			(end -0.120396 0.2794)
			(stroke
				(width 0.1)
				(type default)
			)
			(layer "B.Fab")
		)
		(fp_line
			(start 0.12065 0.3048)
			(end 0.67945 0.3048)
			(stroke
				(width 0.1)
				(type default)
			)
			(layer "B.Fab")
		)
		(fp_line
			(start 0.67945 0.3048)
			(end 0.67945 -0.305054)
			(stroke
				(width 0.1)
				(type default)
			)
			(layer "B.Fab")
		)
		(fp_line
			(start -0.120396 0.2794)
			(end 0.12065 0.2794)
			(stroke
				(width 0.1)
				(type default)
			)
			(layer "B.Fab")
		)
		(fp_line
			(start 0.12065 0.2794)
			(end 0.12065 0.3048)
			(stroke
				(width 0.1)
				(type default)
			)
			(layer "B.Fab")
		)
		(fp_line
			(start -0.12065 -0.2794)
			(end -0.12065 -0.3048)
			(stroke
				(width 0.1)
				(type default)
			)
			(layer "B.Fab")
		)
		(fp_line
			(start 0.12065 -0.2794)
			(end -0.12065 -0.2794)
			(stroke
				(width 0.1)
				(type default)
			)
			(layer "B.Fab")
		)
		(fp_line
			(start -0.67945 -0.3048)
			(end -0.67945 0.3048)
			(stroke
				(width 0.1)
				(type default)
			)
			(layer "B.Fab")
		)
		(fp_line
			(start -0.12065 -0.3048)
			(end -0.67945 -0.3048)
			(stroke
				(width 0.1)
				(type default)
			)
			(layer "B.Fab")
		)
		(fp_line
			(start 0.12065 -0.305054)
			(end 0.12065 -0.2794)
			(stroke
				(width 0.1)
				(type default)
			)
			(layer "B.Fab")
		)
		(fp_line
			(start 0.67945 -0.305054)
			(end 0.12065 -0.305054)
			(stroke
				(width 0.1)
				(type default)
			)
			(layer "B.Fab")
		)
		(pad "1" smd circle
			(at 0.40005 0 90)
			(size 0 0)
			(layers "B.Cu" "B.Mask" "B.Paste")
			(net "PVCCIN_CPU0")
		)
		(pad "2" smd circle
			(at -0.40005 0 90)
			(size 0 0)
			(layers "B.Cu" "B.Mask" "B.Paste")
			(net "GND")
		)
	)
)
